(kicad_pcb
	(version 20260206)
	(generator "pcbnew")
	(generator_version "10.0")
	(general
		(thickness 1.6)
		(legacy_teardrops no)
	)
	(paper "A4")
	(title_block
		(title "Wiwynn_Tioga_Pass_MB.brd")
		(comment 1 "Tioga Pass / footprints 43-49 of 4770")
	)
	(layers
		(0 "F.Cu" signal "TOP")
		(4 "In1.Cu" signal "L2GND")
		(6 "In2.Cu" signal "L3")
		(8 "In3.Cu" signal "L4GND")
		(10 "In4.Cu" signal "L5")
		(12 "In5.Cu" signal "L6GND")
		(14 "In6.Cu" signal "L7VCC")
		(16 "In7.Cu" signal "L8VCC")
		(18 "In8.Cu" signal "L9GND")
		(20 "In9.Cu" signal "L10")
		(22 "In10.Cu" signal "L11GND")
		(24 "In11.Cu" signal "L12")
		(26 "In12.Cu" signal "L13GND")
		(2 "B.Cu" signal "BOTTOM")
		(9 "F.Adhes" user "F.Adhesive")
		(11 "B.Adhes" user "B.Adhesive")
		(13 "F.Paste" user "Package Geometry/Pastemask Top")
		(15 "B.Paste" user "Package Geometry/Pastemask Bottom")
		(5 "F.SilkS" user "Ref Des/Silkscreen Top")
		(7 "B.SilkS" user "Ref Des/Silkscreen Bottom")
		(1 "F.Mask" user "Board Geometry/Soldermask Top")
		(3 "B.Mask" user "Board Geometry/Soldermask Bottom")
		(17 "Dwgs.User" user "User.Drawings")
		(19 "Cmts.User" user "User.Comments")
		(21 "Eco1.User" user "User.Eco1")
		(23 "Eco2.User" user "User.Eco2")
		(25 "Edge.Cuts" user "Board Geometry/Outline")
		(27 "Margin" user)
		(31 "F.CrtYd" user "Package Geometry/Place Bound Top")
		(29 "B.CrtYd" user "Package Geometry/Place Bound Bottom")
		(35 "F.Fab" user "Ref Des/Assembly Top")
		(33 "B.Fab" user "Ref Des/Assembly Bottom")
	)
	(footprint ""
		(layer "F.Cu")
		(at 179.197 -58.166 90)
		(property "Reference" "C4E22"
			(at 0 0 90)
			(layer "F.SilkS")
			(hide yes)
			(effects
				(font
					(size 1.27 1.27)
				)
			)
		)
		(property "Value" ""
			(at 0 0 90)
			(layer "F.Fab")
			(effects
				(font
					(size 1.27 1.27)
				)
			)
		)
		(duplicate_pad_numbers_are_jumpers no)
		(fp_poly
			(pts
				(xy 0.3048 -0.1016) (xy 0.3048 0.9906) (xy -0.3048 0.9906) (xy -0.3048 -0.1016)
			)
			(stroke
				(width 0)
				(type default)
			)
			(fill no)
			(layer "F.CrtYd")
		)
		(fp_line
			(start 0.3048 -0.1016)
			(end -0.3048 -0.1016)
			(stroke
				(width 0.1)
				(type default)
			)
			(layer "F.Fab")
		)
		(fp_line
			(start -0.3048 -0.1016)
			(end -0.3048 0.9906)
			(stroke
				(width 0.1)
				(type default)
			)
			(layer "F.Fab")
		)
		(fp_line
			(start 0.3048 0.9906)
			(end 0.3048 -0.1016)
			(stroke
				(width 0.1)
				(type default)
			)
			(layer "F.Fab")
		)
		(fp_line
			(start -0.3048 0.9906)
			(end 0.3048 0.9906)
			(stroke
				(width 0.1)
				(type default)
			)
			(layer "F.Fab")
		)
		(pad "1" smd rect
			(at 0 0 90)
			(size 0.508 0.508)
			(layers "F.Cu" "F.Mask" "F.Paste")
			(net "VR_PVCCIO_CPU1_PH1_VCIN")
		)
		(pad "2" smd rect
			(at 0 0.889 90)
			(size 0.508 0.508)
			(layers "F.Cu" "F.Mask" "F.Paste")
			(net "GND")
		)
		(zone
			(layer "F.Cu")
			(hatch none 0.5)
			(connect_pads
				(clearance 0)
			)
			(min_thickness 0.25)
			(keepout
				(tracks allowed)
				(vias not_allowed)
				(pads allowed)
				(copperpour not_allowed)
				(footprints allowed)
			)
			(placement
				(enabled no)
				(sheetname "")
			)
			(fill
				(thermal_gap 0.5)
				(thermal_bridge_width 0.5)
				(island_removal_mode 0)
			)
			(polygon
				(pts
					(xy 179.451 -57.912) (xy 179.451 -58.42) (xy 179.832 -58.42) (xy 179.832 -57.912)
				)
			)
		)
		(zone
			(layer "F.Cu")
			(hatch none 0.5)
			(connect_pads
				(clearance 0)
			)
			(min_thickness 0.25)
			(keepout
				(tracks not_allowed)
				(vias allowed)
				(pads allowed)
				(copperpour not_allowed)
				(footprints allowed)
			)
			(placement
				(enabled no)
				(sheetname "")
			)
			(fill
				(thermal_gap 0.5)
				(thermal_bridge_width 0.5)
				(island_removal_mode 0)
			)
			(polygon
				(pts
					(xy 179.832 -57.912) (xy 179.832 -58.42) (xy 179.451 -58.42) (xy 179.451 -57.912)
				)
			)
		)
	)
	(footprint ""
		(layer "F.Cu")
		(at 400.558 -156.718)
		(property "Reference" "R8A1"
			(at 0 0 0)
			(layer "F.SilkS")
			(hide yes)
			(effects
				(font
					(size 1.27 1.27)
				)
			)
		)
		(property "Value" ""
			(at 0 0 0)
			(layer "F.Fab")
			(effects
				(font
					(size 1.27 1.27)
				)
			)
		)
		(duplicate_pad_numbers_are_jumpers no)
		(fp_poly
			(pts
				(xy -0.2794 -0.1016) (xy 0.2794 -0.1016) (xy 0.2794 0.9906) (xy -0.2794 0.9906)
			)
			(stroke
				(width 0)
				(type default)
			)
			(fill no)
			(layer "F.CrtYd")
		)
		(fp_line
			(start -0.2794 -0.1016)
			(end -0.2794 0.9906)
			(stroke
				(width 0.1)
				(type default)
			)
			(layer "F.Fab")
		)
		(fp_line
			(start -0.2794 0.9906)
			(end 0.2794 0.9906)
			(stroke
				(width 0.1)
				(type default)
			)
			(layer "F.Fab")
		)
		(fp_line
			(start 0.2794 -0.1016)
			(end -0.2794 -0.1016)
			(stroke
				(width 0.1)
				(type default)
			)
			(layer "F.Fab")
		)
		(fp_line
			(start 0.2794 0.9906)
			(end 0.2794 -0.1016)
			(stroke
				(width 0.1)
				(type default)
			)
			(layer "F.Fab")
		)
		(pad "1" smd rect
			(at 0 0)
			(size 0.508 0.508)
			(layers "F.Cu" "F.Mask" "F.Paste")
			(net "VSENSE_PVNN_PCH_STBY_AVSP")
		)
		(pad "2" smd rect
			(at 0 0.889)
			(size 0.508 0.508)
			(layers "F.Cu" "F.Mask" "F.Paste")
			(net "VR_PVNN_PCH_AVSP")
		)
		(zone
			(layer "F.Cu")
			(hatch none 0.5)
			(connect_pads
				(clearance 0)
			)
			(min_thickness 0.25)
			(keepout
				(tracks allowed)
				(vias not_allowed)
				(pads allowed)
				(copperpour not_allowed)
				(footprints allowed)
			)
			(placement
				(enabled no)
				(sheetname "")
			)
			(fill
				(thermal_gap 0.5)
				(thermal_bridge_width 0.5)
				(island_removal_mode 0)
			)
			(polygon
				(pts
					(xy 400.304 -156.464) (xy 400.812 -156.464) (xy 400.812 -156.083) (xy 400.304 -156.083)
				)
			)
		)
		(zone
			(layer "F.Cu")
			(hatch none 0.5)
			(connect_pads
				(clearance 0)
			)
			(min_thickness 0.25)
			(keepout
				(tracks not_allowed)
				(vias allowed)
				(pads allowed)
				(copperpour not_allowed)
				(footprints allowed)
			)
			(placement
				(enabled no)
				(sheetname "")
			)
			(fill
				(thermal_gap 0.5)
				(thermal_bridge_width 0.5)
				(island_removal_mode 0)
			)
			(polygon
				(pts
					(xy 400.304 -156.083) (xy 400.812 -156.083) (xy 400.812 -156.464) (xy 400.304 -156.464)
				)
			)
		)
	)
	(footprint ""
		(layer "F.Cu")
		(at 154.305 -29.6418 90)
		(property "Reference" "R3F2"
			(at 0 0 90)
			(layer "F.SilkS")
			(hide yes)
			(effects
				(font
					(size 1.27 1.27)
				)
			)
		)
		(property "Value" ""
			(at 0 0 90)
			(layer "F.Fab")
			(effects
				(font
					(size 1.27 1.27)
				)
			)
		)
		(duplicate_pad_numbers_are_jumpers no)
		(fp_poly
			(pts
				(xy -0.2794 -0.1016) (xy 0.2794 -0.1016) (xy 0.2794 0.9906) (xy -0.2794 0.9906)
			)
			(stroke
				(width 0)
				(type default)
			)
			(fill no)
			(layer "F.CrtYd")
		)
		(fp_line
			(start 0.2794 -0.1016)
			(end -0.2794 -0.1016)
			(stroke
				(width 0.1)
				(type default)
			)
			(layer "F.Fab")
		)
		(fp_line
			(start -0.2794 -0.1016)
			(end -0.2794 0.9906)
			(stroke
				(width 0.1)
				(type default)
			)
			(layer "F.Fab")
		)
		(fp_line
			(start 0.2794 0.9906)
			(end 0.2794 -0.1016)
			(stroke
				(width 0.1)
				(type default)
			)
			(layer "F.Fab")
		)
		(fp_line
			(start -0.2794 0.9906)
			(end 0.2794 0.9906)
			(stroke
				(width 0.1)
				(type default)
			)
			(layer "F.Fab")
		)
		(pad "1" smd rect
			(at 0 0 90)
			(size 0.508 0.508)
			(layers "F.Cu" "F.Mask" "F.Paste")
			(net "CLK_156M_OSC_BRD_CPU1_DN")
		)
		(pad "2" smd rect
			(at 0 0.889 90)
			(size 0.508 0.508)
			(layers "F.Cu" "F.Mask" "F.Paste")
			(net "CLK_156M_OSC_CPU1_HFI_DN")
		)
		(zone
			(layer "F.Cu")
			(hatch none 0.5)
			(connect_pads
				(clearance 0)
			)
			(min_thickness 0.25)
			(keepout
				(tracks allowed)
				(vias not_allowed)
				(pads allowed)
				(copperpour not_allowed)
				(footprints allowed)
			)
			(placement
				(enabled no)
				(sheetname "")
			)
			(fill
				(thermal_gap 0.5)
				(thermal_bridge_width 0.5)
				(island_removal_mode 0)
			)
			(polygon
				(pts
					(xy 154.559 -29.3878) (xy 154.559 -29.8958) (xy 154.94 -29.8958) (xy 154.94 -29.3878)
				)
			)
		)
		(zone
			(layer "F.Cu")
			(hatch none 0.5)
			(connect_pads
				(clearance 0)
			)
			(min_thickness 0.25)
			(keepout
				(tracks not_allowed)
				(vias allowed)
				(pads allowed)
				(copperpour not_allowed)
				(footprints allowed)
			)
			(placement
				(enabled no)
				(sheetname "")
			)
			(fill
				(thermal_gap 0.5)
				(thermal_bridge_width 0.5)
				(island_removal_mode 0)
			)
			(polygon
				(pts
					(xy 154.94 -29.3878) (xy 154.94 -29.8958) (xy 154.559 -29.8958) (xy 154.559 -29.3878)
				)
			)
		)
	)
	(footprint ""
		(layer "F.Cu")
		(at 166.497 -3.048 180)
		(property "Reference" "C4G20"
			(at 0 0 180)
			(layer "F.SilkS")
			(hide yes)
			(effects
				(font
					(size 1.27 1.27)
				)
			)
		)
		(property "Value" ""
			(at 0 0 180)
			(layer "F.Fab")
			(effects
				(font
					(size 1.27 1.27)
				)
			)
		)
		(duplicate_pad_numbers_are_jumpers no)
		(fp_rect
			(start -0.7239 1.9939)
			(end 0.7239 -0.2159)
			(stroke
				(width 0)
				(type default)
			)
			(fill no)
			(layer "F.CrtYd")
		)
		(fp_line
			(start 0.7239 1.9939)
			(end 0.7239 -0.2159)
			(stroke
				(width 0.1)
				(type default)
			)
			(layer "F.Fab")
		)
		(fp_line
			(start 0.7239 -0.2159)
			(end -0.7239 -0.2159)
			(stroke
				(width 0.1)
				(type default)
			)
			(layer "F.Fab")
		)
		(fp_line
			(start -0.7239 1.9939)
			(end 0.7239 1.9939)
			(stroke
				(width 0.1)
				(type default)
			)
			(layer "F.Fab")
		)
		(fp_line
			(start -0.7239 -0.2159)
			(end -0.7239 1.9939)
			(stroke
				(width 0.1)
				(type default)
			)
			(layer "F.Fab")
		)
		(pad "1" smd rect
			(at 0 0 180)
			(size 1.27 1.016)
			(layers "F.Cu" "F.Mask" "F.Paste")
			(net "PVTT_GHJ")
		)
		(pad "2" smd rect
			(at 0 1.778 180)
			(size 1.27 1.016)
			(layers "F.Cu" "F.Mask" "F.Paste")
			(net "GND")
		)
		(zone
			(layer "F.Cu")
			(hatch none 0.5)
			(connect_pads
				(clearance 0)
			)
			(min_thickness 0.25)
			(keepout
				(tracks not_allowed)
				(vias allowed)
				(pads allowed)
				(copperpour not_allowed)
				(footprints allowed)
			)
			(placement
				(enabled no)
				(sheetname "")
			)
			(fill
				(thermal_gap 0.5)
				(thermal_bridge_width 0.5)
				(island_removal_mode 0)
			)
			(polygon
				(pts
					(xy 167.132 -4.318) (xy 165.862 -4.318) (xy 165.862 -3.556) (xy 167.132 -3.556)
				)
			)
		)
	)
	(footprint ""
		(layer "F.Cu")
		(at 415.7345 -110.617 -90)
		(property "Reference" "R2M3"
			(at 0 0 270)
			(layer "F.SilkS")
			(hide yes)
			(effects
				(font
					(size 1.27 1.27)
				)
			)
		)
		(property "Value" ""
			(at 0 0 270)
			(layer "F.Fab")
			(effects
				(font
					(size 1.27 1.27)
				)
			)
		)
		(duplicate_pad_numbers_are_jumpers no)
		(fp_poly
			(pts
				(xy -0.2794 -0.1016) (xy 0.2794 -0.1016) (xy 0.2794 0.9906) (xy -0.2794 0.9906)
			)
			(stroke
				(width 0)
				(type default)
			)
			(fill no)
			(layer "F.CrtYd")
		)
		(fp_line
			(start -0.2794 0.9906)
			(end 0.2794 0.9906)
			(stroke
				(width 0.1)
				(type default)
			)
			(layer "F.Fab")
		)
		(fp_line
			(start 0.2794 0.9906)
			(end 0.2794 -0.1016)
			(stroke
				(width 0.1)
				(type default)
			)
			(layer "F.Fab")
		)
		(fp_line
			(start -0.2794 -0.1016)
			(end -0.2794 0.9906)
			(stroke
				(width 0.1)
				(type default)
			)
			(layer "F.Fab")
		)
		(fp_line
			(start 0.2794 -0.1016)
			(end -0.2794 -0.1016)
			(stroke
				(width 0.1)
				(type default)
			)
			(layer "F.Fab")
		)
		(pad "1" smd rect
			(at 0 0 270)
			(size 0.508 0.508)
			(layers "F.Cu" "F.Mask" "F.Paste")
			(net "FM_PCH_PLD_DATA_R")
		)
		(pad "2" smd rect
			(at 0 0.889 270)
			(size 0.508 0.508)
			(layers "F.Cu" "F.Mask" "F.Paste")
			(net "FM_PCH_PLD_DATA")
		)
		(zone
			(layer "F.Cu")
			(hatch none 0.5)
			(connect_pads
				(clearance 0)
			)
			(min_thickness 0.25)
			(keepout
				(tracks not_allowed)
				(vias allowed)
				(pads allowed)
				(copperpour not_allowed)
				(footprints allowed)
			)
			(placement
				(enabled no)
				(sheetname "")
			)
			(fill
				(thermal_gap 0.5)
				(thermal_bridge_width 0.5)
				(island_removal_mode 0)
			)
			(polygon
				(pts
					(xy 415.0995 -110.871) (xy 415.0995 -110.363) (xy 415.4805 -110.363) (xy 415.4805 -110.871)
				)
			)
		)
		(zone
			(layer "F.Cu")
			(hatch none 0.5)
			(connect_pads
				(clearance 0)
			)
			(min_thickness 0.25)
			(keepout
				(tracks allowed)
				(vias not_allowed)
				(pads allowed)
				(copperpour not_allowed)
				(footprints allowed)
			)
			(placement
				(enabled no)
				(sheetname "")
			)
			(fill
				(thermal_gap 0.5)
				(thermal_bridge_width 0.5)
				(island_removal_mode 0)
			)
			(polygon
				(pts
					(xy 415.4805 -110.871) (xy 415.4805 -110.363) (xy 415.0995 -110.363) (xy 415.0995 -110.871)
				)
			)
		)
	)
	(footprint ""
		(layer "F.Cu")
		(at 451.85838 -38.2905 90)
		(property "Reference" "R25W49"
			(at 0 0 90)
			(layer "F.SilkS")
			(hide yes)
			(effects
				(font
					(size 1.27 1.27)
				)
			)
		)
		(property "Value" "*"
			(at 0.064008 -4.108196 90)
			(unlocked yes)
			(layer "F.Fab")
			(hide yes)
			(effects
				(font
					(size 1.27 1.016)
					(thickness 0.1524)
				)
			)
		)
		(property "Device Type" "120R2F-GP_RCL_GP-120R2F-GP,64.A"
			(at 0.064008 -5.632196 90)
			(unlocked yes)
			(layer "F.Fab")
			(hide yes)
			(effects
				(font
					(size 1.27 1.016)
					(thickness 0.1524)
				)
			)
		)
		(duplicate_pad_numbers_are_jumpers no)
		(fp_line
			(start 0.508 -0.9398)
			(end -0.508 -0.9398)
			(stroke
				(width 0.1524)
				(type default)
			)
			(layer "F.SilkS")
		)
		(fp_line
			(start -0.508 -0.9398)
			(end -0.508 0.9398)
			(stroke
				(width 0.1524)
				(type default)
			)
			(layer "F.SilkS")
		)
		(fp_rect
			(start -0.508 0.9398)
			(end 0.508 -0.9398)
			(stroke
				(width 0)
				(type default)
			)
			(fill no)
			(layer "F.CrtYd")
		)
		(fp_rect
			(start -0.508 0.9398)
			(end 0.508 -0.9398)
			(stroke
				(width 0)
				(type default)
			)
			(fill no)
			(layer "F.Fab")
		)
		(pad "1" smd custom
			(at 0 -0.4445 90)
			(size 0.1397 0.1397)
			(layers "F.Cu" "F.Mask" "F.Paste")
			(net "BMC_M_A11")
			(options
				(clearance outline)
				(anchor circle)
			)
			(primitives
				(gr_poly
					(pts
						(arc
							(start -0.1778 -0.2794)
							(mid -0.249642 -0.249642)
							(end -0.2794 -0.1778)
						)
						(arc
							(start -0.2794 0.1778)
							(mid -0.249642 0.249642)
							(end -0.1778 0.2794)
						)
						(arc
							(start 0.1778 0.2794)
							(mid 0.249642 0.249642)
							(end 0.2794 0.1778)
						)
						(arc
							(start 0.2794 -0.1778)
							(mid 0.249642 -0.249642)
							(end 0.1778 -0.2794)
						)
					)
					(width 0)
					(fill yes)
				)
			)
		)
		(pad "2" smd custom
			(at 0 0.4445 90)
			(size 0.1397 0.1397)
			(layers "F.Cu" "F.Mask" "F.Paste")
			(net "P1V2_AUX_BMC")
			(options
				(clearance outline)
				(anchor circle)
			)
			(primitives
				(gr_poly
					(pts
						(arc
							(start -0.1778 -0.2794)
							(mid -0.249642 -0.249642)
							(end -0.2794 -0.1778)
						)
						(arc
							(start -0.2794 0.1778)
							(mid -0.249642 0.249642)
							(end -0.1778 0.2794)
						)
						(arc
							(start 0.1778 0.2794)
							(mid 0.249642 0.249642)
							(end 0.2794 0.1778)
						)
						(arc
							(start 0.2794 -0.1778)
							(mid 0.249642 -0.249642)
							(end 0.1778 -0.2794)
						)
					)
					(width 0)
					(fill yes)
				)
			)
		)
	)
	(footprint ""
		(layer "F.Cu")
		(at 180.381148 -73.85685 -90)
		(property "Reference" "C4D26"
			(at 0 0 270)
			(layer "F.SilkS")
			(hide yes)
			(effects
				(font
					(size 1.27 1.27)
				)
			)
		)
		(property "Value" ""
			(at 0 0 270)
			(layer "F.Fab")
			(effects
				(font
					(size 1.27 1.27)
				)
			)
		)
		(duplicate_pad_numbers_are_jumpers no)
		(fp_rect
			(start 0.3048 -0.1016)
			(end -0.3048 0.9906)
			(stroke
				(width 0)
				(type default)
			)
			(fill no)
			(layer "F.CrtYd")
		)
		(fp_line
			(start -0.3048 0.9906)
			(end 0.3048 0.9906)
			(stroke
				(width 0.1)
				(type default)
			)
			(layer "F.Fab")
		)
		(fp_line
			(start 0.3048 0.9906)
			(end 0.3048 -0.1016)
			(stroke
				(width 0.1)
				(type default)
			)
			(layer "F.Fab")
		)
		(fp_line
			(start -0.3048 -0.1016)
			(end -0.3048 0.9906)
			(stroke
				(width 0.1)
				(type default)
			)
			(layer "F.Fab")
		)
		(fp_line
			(start 0.3048 -0.1016)
			(end -0.3048 -0.1016)
			(stroke
				(width 0.1)
				(type default)
			)
			(layer "F.Fab")
		)
		(pad "1" smd rect
			(at 0 0 270)
			(size 0.508 0.508)
			(layers "F.Cu" "F.Mask" "F.Paste")
			(net "VR_PVCCIN_CPU0_VD12")
		)
		(pad "2" smd rect
			(at 0 0.889 270)
			(size 0.508 0.508)
			(layers "F.Cu" "F.Mask" "F.Paste")
			(net "GND")
		)
		(zone
			(layer "F.Cu")
			(hatch none 0.5)
			(connect_pads
				(clearance 0)
			)
			(min_thickness 0.25)
			(keepout
				(tracks not_allowed)
				(vias allowed)
				(pads allowed)
				(copperpour not_allowed)
				(footprints allowed)
			)
			(placement
				(enabled no)
				(sheetname "")
			)
			(fill
				(thermal_gap 0.5)
				(thermal_bridge_width 0.5)
				(island_removal_mode 0)
			)
			(polygon
				(pts
					(xy 180.127148 -73.60285) (xy 180.127148 -74.11085) (xy 179.746148 -74.11085) (xy 179.746148 -73.60285)
				)
			)
		)
		(zone
			(layer "F.Cu")
			(hatch none 0.5)
			(connect_pads
				(clearance 0)
			)
			(min_thickness 0.25)
			(keepout
				(tracks allowed)
				(vias not_allowed)
				(pads allowed)
				(copperpour not_allowed)
				(footprints allowed)
			)
			(placement
				(enabled no)
				(sheetname "")
			)
			(fill
				(thermal_gap 0.5)
				(thermal_bridge_width 0.5)
				(island_removal_mode 0)
			)
			(polygon
				(pts
					(xy 180.127148 -73.60285) (xy 180.127148 -74.11085) (xy 179.746148 -74.11085) (xy 179.746148 -73.60285)
				)
			)
		)
	)
)
